(kicad_pcb
	(version 20260206)
	(generator "pcbnew")
	(generator_version "10.0")
	(general
		(thickness 1.6)
		(legacy_teardrops no)
	)
	(paper "A4")
	(title_block
		(title "9052_F0T_PDB_Converter_Brick_F_V03_1208_1600_OCP.brd")
		(comment 1 "Grand Teton / footprints 132-138 of 578")
	)
	(layers
		(0 "F.Cu" signal "TOP")
		(4 "In1.Cu" signal "GND")
		(6 "In2.Cu" signal "IN1")
		(8 "In3.Cu" signal "GND1")
		(10 "In4.Cu" signal "VCC")
		(12 "In5.Cu" signal "VCC1")
		(14 "In6.Cu" signal "GND2")
		(16 "In7.Cu" signal "IN2")
		(18 "In8.Cu" signal "GND3")
		(2 "B.Cu" signal "BOTTOM")
		(9 "F.Adhes" user "F.Adhesive")
		(11 "B.Adhes" user "B.Adhesive")
		(13 "F.Paste" user "Package Geometry/Pastemask Top")
		(15 "B.Paste" user "Package Geometry/Pastemask Bottom")
		(5 "F.SilkS" user "Ref Des/Silkscreen Top")
		(7 "B.SilkS" user "Ref Des/Silkscreen Bottom")
		(1 "F.Mask" user "Board Geometry/Soldermask Top")
		(3 "B.Mask" user "Board Geometry/Soldermask Bottom")
		(17 "Dwgs.User" user "User.Drawings")
		(19 "Cmts.User" user "User.Comments")
		(21 "Eco1.User" user "User.Eco1")
		(23 "Eco2.User" user "User.Eco2")
		(25 "Edge.Cuts" user "Board Geometry/Outline")
		(27 "Margin" user)
		(31 "F.CrtYd" user "Package Geometry/Place Bound Top")
		(29 "B.CrtYd" user "Package Geometry/Place Bound Bottom")
		(35 "F.Fab" user "Ref Des/Assembly Top")
		(33 "B.Fab" user "Ref Des/Assembly Bottom")
	)
	(footprint ""
		(layer "F.Cu")
		(at 209.931 -91.5924)
		(property "Reference" "R60"
			(at 0 0 0)
			(layer "F.SilkS")
			(hide yes)
			(effects
				(font
					(size 1.27 1.27)
				)
			)
		)
		(property "Value" ""
			(at 0 0 0)
			(layer "F.Fab")
			(effects
				(font
					(size 1.27 1.27)
				)
			)
		)
		(duplicate_pad_numbers_are_jumpers no)
		(fp_line
			(start -2.234946 -0.9271)
			(end 2.234946 -0.9271)
			(stroke
				(width 0.1524)
				(type default)
			)
			(layer "F.SilkS")
		)
		(fp_line
			(start -2.234946 0.9271)
			(end -2.234946 -0.9271)
			(stroke
				(width 0.1524)
				(type default)
			)
			(layer "F.SilkS")
		)
		(fp_line
			(start 2.234946 -0.9271)
			(end 2.234946 0.9271)
			(stroke
				(width 0.1524)
				(type default)
			)
			(layer "F.SilkS")
		)
		(fp_line
			(start 2.234946 0.9271)
			(end -2.234946 0.9271)
			(stroke
				(width 0.1524)
				(type default)
			)
			(layer "F.SilkS")
		)
		(fp_line
			(start -1.575054 -0.824992)
			(end -1.575054 0.824992)
			(stroke
				(width 0.1)
				(type default)
			)
			(layer "F.Fab")
		)
		(fp_line
			(start -1.575054 0.824992)
			(end 1.575054 0.824992)
			(stroke
				(width 0.1)
				(type default)
			)
			(layer "F.Fab")
		)
		(fp_line
			(start 1.575054 -0.824992)
			(end -1.575054 -0.824992)
			(stroke
				(width 0.1)
				(type default)
			)
			(layer "F.Fab")
		)
		(fp_line
			(start 1.575054 0.824992)
			(end 1.575054 -0.824992)
			(stroke
				(width 0.1)
				(type default)
			)
			(layer "F.Fab")
		)
		(pad "1" smd rect
			(at -1.599946 0)
			(size 1.016 1.6002)
			(layers "F.Cu" "F.Mask" "F.Paste")
			(net "LED_D1_R2")
		)
		(pad "2" smd rect
			(at 1.599946 0)
			(size 1.016 1.6002)
			(layers "F.Cu" "F.Mask" "F.Paste")
			(net "LED_D1_R3")
		)
	)
	(footprint ""
		(layer "F.Cu")
		(at 301.602394 -86.8045)
		(property "Reference" "PR6955"
			(at 0 0 0)
			(layer "F.SilkS")
			(hide yes)
			(effects
				(font
					(size 1.27 1.27)
				)
			)
		)
		(property "Value" ""
			(at 0 0 0)
			(layer "F.Fab")
			(effects
				(font
					(size 1.27 1.27)
				)
			)
		)
		(duplicate_pad_numbers_are_jumpers no)
		(fp_line
			(start -1.2954 -0.5842)
			(end 1.2954 -0.5842)
			(stroke
				(width 0.1524)
				(type default)
			)
			(layer "F.SilkS")
		)
		(fp_line
			(start -1.2954 0.5842)
			(end -1.2954 -0.5842)
			(stroke
				(width 0.1524)
				(type default)
			)
			(layer "F.SilkS")
		)
		(fp_line
			(start 1.2954 -0.5842)
			(end 1.2954 0.5842)
			(stroke
				(width 0.1524)
				(type default)
			)
			(layer "F.SilkS")
		)
		(fp_line
			(start 1.2954 0.5842)
			(end -1.2954 0.5842)
			(stroke
				(width 0.1524)
				(type default)
			)
			(layer "F.SilkS")
		)
		(fp_line
			(start -1.1938 -0.406654)
			(end -0.8636 -0.406654)
			(stroke
				(width 0.1)
				(type default)
			)
			(layer "F.Fab")
		)
		(fp_line
			(start -1.1938 0.4064)
			(end -1.1938 -0.406654)
			(stroke
				(width 0.1)
				(type default)
			)
			(layer "F.Fab")
		)
		(fp_line
			(start -0.8636 -0.4572)
			(end 0.8636 -0.4572)
			(stroke
				(width 0.1)
				(type default)
			)
			(layer "F.Fab")
		)
		(fp_line
			(start -0.8636 -0.406654)
			(end -0.8636 -0.4572)
			(stroke
				(width 0.1)
				(type default)
			)
			(layer "F.Fab")
		)
		(fp_line
			(start -0.8636 0.4064)
			(end -1.1938 0.4064)
			(stroke
				(width 0.1)
				(type default)
			)
			(layer "F.Fab")
		)
		(fp_line
			(start -0.8636 0.4318)
			(end -0.8636 0.4064)
			(stroke
				(width 0.1)
				(type default)
			)
			(layer "F.Fab")
		)
		(fp_line
			(start -0.8636 0.4572)
			(end -0.8636 0.4318)
			(stroke
				(width 0.1)
				(type default)
			)
			(layer "F.Fab")
		)
		(fp_line
			(start 0.8636 -0.4572)
			(end 0.8636 -0.406654)
			(stroke
				(width 0.1)
				(type default)
			)
			(layer "F.Fab")
		)
		(fp_line
			(start 0.8636 -0.406654)
			(end 1.1938 -0.406654)
			(stroke
				(width 0.1)
				(type default)
			)
			(layer "F.Fab")
		)
		(fp_line
			(start 0.8636 0.4064)
			(end 0.8636 0.4572)
			(stroke
				(width 0.1)
				(type default)
			)
			(layer "F.Fab")
		)
		(fp_line
			(start 0.8636 0.4572)
			(end -0.8636 0.4572)
			(stroke
				(width 0.1)
				(type default)
			)
			(layer "F.Fab")
		)
		(fp_line
			(start 1.1938 -0.406654)
			(end 1.1938 0.4064)
			(stroke
				(width 0.1)
				(type default)
			)
			(layer "F.Fab")
		)
		(fp_line
			(start 1.1938 0.4064)
			(end 0.8636 0.4064)
			(stroke
				(width 0.1)
				(type default)
			)
			(layer "F.Fab")
		)
		(pad "1" smd rect
			(at -0.7366 0 270)
			(size 0.7112 0.8128)
			(layers "F.Cu" "F.Mask" "F.Paste")
			(net "P52V_HS_4287_S2P")
		)
		(pad "2" smd rect
			(at 0.7366 0 270)
			(size 0.7112 0.8128)
			(layers "F.Cu" "F.Mask" "F.Paste")
			(net "P52V_HS1_SENSE_P_R2")
		)
	)
	(footprint ""
		(layer "F.Cu")
		(at 256.794 -24.892 180)
		(property "Reference" "JP2"
			(at -1.4859 -2.32537 0)
			(unlocked yes)
			(layer "F.SilkS")
			(effects
				(font
					(size 0.7874 0.5842)
					(thickness 0.1524)
				)
				(justify left)
			)
		)
		(property "Value" ""
			(at 0 0 180)
			(layer "F.Fab")
			(effects
				(font
					(size 1.27 1.27)
				)
			)
		)
		(duplicate_pad_numbers_are_jumpers no)
		(fp_line
			(start 1.234948 6.415024)
			(end -1.234948 6.415024)
			(stroke
				(width 0.1524)
				(type default)
			)
			(layer "F.SilkS")
		)
		(fp_line
			(start 1.234948 -1.335024)
			(end 1.234948 6.415024)
			(stroke
				(width 0.1524)
				(type default)
			)
			(layer "F.SilkS")
		)
		(fp_line
			(start -1.234948 6.415024)
			(end -1.234948 -1.335024)
			(stroke
				(width 0.1524)
				(type default)
			)
			(layer "F.SilkS")
		)
		(fp_line
			(start -1.234948 -1.335024)
			(end 1.234948 -1.335024)
			(stroke
				(width 0.1524)
				(type default)
			)
			(layer "F.SilkS")
		)
		(fp_poly
			(pts
				(xy 0.508 -2.530348) (xy -0.508 -2.530348) (xy 0 -1.514348)
			)
			(stroke
				(width 0)
				(type default)
			)
			(fill yes)
			(layer "F.SilkS")
		)
		(fp_line
			(start 1.234948 6.415024)
			(end -1.234948 6.415024)
			(stroke
				(width 0.1)
				(type default)
			)
			(layer "F.Fab")
		)
		(fp_line
			(start 1.234948 -1.335024)
			(end 1.234948 6.415024)
			(stroke
				(width 0.1)
				(type default)
			)
			(layer "F.Fab")
		)
		(fp_line
			(start -1.234948 6.415024)
			(end -1.234948 -1.335024)
			(stroke
				(width 0.1)
				(type default)
			)
			(layer "F.Fab")
		)
		(fp_line
			(start -1.234948 -1.335024)
			(end 1.234948 -1.335024)
			(stroke
				(width 0.1)
				(type default)
			)
			(layer "F.Fab")
		)
		(fp_poly
			(pts
				(xy 0.508 -2.530348) (xy -0.508 -2.530348) (xy 0 -1.514348)
			)
			(stroke
				(width 0)
				(type default)
			)
			(fill yes)
			(layer "F.Fab")
		)
		(fp_text user "3"
			(at 0.10668 7.527798 270)
			(unlocked yes)
			(layer "F.SilkS")
			(effects
				(font
					(size 0.7874 0.5842)
					(thickness 0.1524)
				)
				(justify left)
			)
		)
		(fp_text user "3"
			(at -0.00127 6.640576 90)
			(unlocked yes)
			(layer "B.SilkS")
			(effects
				(font
					(size 0.7874 0.5842)
					(thickness 0.1524)
				)
				(justify left mirror)
			)
		)
		(fp_text user "1"
			(at -0.00127 -0.954024 90)
			(unlocked yes)
			(layer "B.SilkS")
			(effects
				(font
					(size 0.7874 0.5842)
					(thickness 0.1524)
				)
				(justify left mirror)
			)
		)
		(fp_text user "3"
			(at -0.00127 6.640576 90)
			(unlocked yes)
			(layer "B.Fab")
			(effects
				(font
					(size 0.7874 0.5842)
					(thickness 0.1524)
				)
				(justify left mirror)
			)
		)
		(fp_text user "1"
			(at -0.00127 -0.954024 90)
			(unlocked yes)
			(layer "B.Fab")
			(effects
				(font
					(size 0.7874 0.5842)
					(thickness 0.1524)
				)
				(justify left mirror)
			)
		)
		(fp_text user "3"
			(at -0.009652 6.5659 90)
			(unlocked yes)
			(layer "F.Fab")
			(effects
				(font
					(size 0.7874 0.5842)
					(thickness 0.1524)
				)
				(justify left)
			)
		)
		(pad "1" thru_hole rect
			(at 0 0 90)
			(size 1.6764 1.6764)
			(drill 1.1684)
			(layers "*.Cu" "*.Mask")
			(remove_unused_layers no)
			(net "SMB_P52V_VPDB_DEBUG_SDA")
			(clearance 0)
			(padstack
				(mode front_inner_back)
				(layer "Inner"
					(shape circle)
					(size 1.6764 1.6764)
					(clearance 0)
				)
				(layer "B.Cu"
					(shape rect)
					(size 1.6764 1.6764)
					(clearance 0)
				)
			)
		)
		(pad "2" thru_hole circle
			(at 0 2.54 90)
			(size 1.6764 1.6764)
			(drill 1.1684)
			(layers "*.Cu" "*.Mask")
			(remove_unused_layers no)
			(net "GND")
			(clearance 0)
		)
		(pad "3" thru_hole circle
			(at 0 5.08 90)
			(size 1.6764 1.6764)
			(drill 1.1684)
			(layers "*.Cu" "*.Mask")
			(remove_unused_layers no)
			(net "SMB_P52V_VPDB_DEBUG_SCL")
			(clearance 0)
		)
	)
	(footprint ""
		(layer "F.Cu")
		(at 279.010872 -38.571424)
		(property "Reference" "R147"
			(at 0 0 0)
			(layer "F.SilkS")
			(hide yes)
			(effects
				(font
					(size 1.27 1.27)
				)
			)
		)
		(property "Value" ""
			(at 0 0 0)
			(layer "F.Fab")
			(effects
				(font
					(size 1.27 1.27)
				)
			)
		)
		(duplicate_pad_numbers_are_jumpers no)
		(fp_line
			(start -0.7874 -0.4064)
			(end 0.7874 -0.4064)
			(stroke
				(width 0.1524)
				(type default)
			)
			(layer "F.SilkS")
		)
		(fp_line
			(start -0.7874 0.4064)
			(end -0.7874 -0.4064)
			(stroke
				(width 0.1524)
				(type default)
			)
			(layer "F.SilkS")
		)
		(fp_line
			(start 0.7874 -0.4064)
			(end 0.7874 0.4064)
			(stroke
				(width 0.1524)
				(type default)
			)
			(layer "F.SilkS")
		)
		(fp_line
			(start 0.7874 0.4064)
			(end -0.7874 0.4064)
			(stroke
				(width 0.1524)
				(type default)
			)
			(layer "F.SilkS")
		)
		(fp_line
			(start -0.67945 -0.305054)
			(end -0.12065 -0.305054)
			(stroke
				(width 0.1)
				(type default)
			)
			(layer "F.Fab")
		)
		(fp_line
			(start -0.67945 0.3048)
			(end -0.67945 -0.305054)
			(stroke
				(width 0.1)
				(type default)
			)
			(layer "F.Fab")
		)
		(fp_line
			(start -0.12065 -0.305054)
			(end -0.12065 -0.2794)
			(stroke
				(width 0.1)
				(type default)
			)
			(layer "F.Fab")
		)
		(fp_line
			(start -0.12065 -0.2794)
			(end 0.12065 -0.2794)
			(stroke
				(width 0.1)
				(type default)
			)
			(layer "F.Fab")
		)
		(fp_line
			(start -0.12065 0.2794)
			(end -0.12065 0.3048)
			(stroke
				(width 0.1)
				(type default)
			)
			(layer "F.Fab")
		)
		(fp_line
			(start -0.12065 0.3048)
			(end -0.67945 0.3048)
			(stroke
				(width 0.1)
				(type default)
			)
			(layer "F.Fab")
		)
		(fp_line
			(start 0.120396 0.2794)
			(end -0.12065 0.2794)
			(stroke
				(width 0.1)
				(type default)
			)
			(layer "F.Fab")
		)
		(fp_line
			(start 0.120396 0.3048)
			(end 0.120396 0.2794)
			(stroke
				(width 0.1)
				(type default)
			)
			(layer "F.Fab")
		)
		(fp_line
			(start 0.12065 -0.3048)
			(end 0.67945 -0.3048)
			(stroke
				(width 0.1)
				(type default)
			)
			(layer "F.Fab")
		)
		(fp_line
			(start 0.12065 -0.2794)
			(end 0.12065 -0.3048)
			(stroke
				(width 0.1)
				(type default)
			)
			(layer "F.Fab")
		)
		(fp_line
			(start 0.67945 -0.3048)
			(end 0.67945 0.3048)
			(stroke
				(width 0.1)
				(type default)
			)
			(layer "F.Fab")
		)
		(fp_line
			(start 0.67945 0.3048)
			(end 0.120396 0.3048)
			(stroke
				(width 0.1)
				(type default)
			)
			(layer "F.Fab")
		)
		(pad "1" smd circle
			(at -0.40005 0)
			(size 0 0)
			(layers "F.Cu" "F.Mask" "F.Paste")
			(net "P3V3_AUX")
		)
		(pad "2" smd circle
			(at 0.40005 0)
			(size 0 0)
			(layers "F.Cu" "F.Mask" "F.Paste")
			(net "SMB_P52V_HSC_SDA")
		)
	)
	(footprint ""
		(layer "F.Cu")
		(at 131.191 -60.96)
		(property "Reference" "PC69"
			(at -1.651 -3.52933 0)
			(unlocked yes)
			(layer "F.SilkS")
			(effects
				(font
					(size 0.7874 0.5842)
					(thickness 0.1524)
				)
				(justify left)
			)
		)
		(property "Value" ""
			(at 0 0 0)
			(layer "F.Fab")
			(effects
				(font
					(size 1.27 1.27)
				)
			)
		)
		(duplicate_pad_numbers_are_jumpers no)
		(fp_line
			(start 5.2578 2.499868)
			(end -5.2578 2.499868)
			(stroke
				(width 0.1524)
				(type default)
			)
			(layer "F.SilkS")
		)
		(fp_circle
			(center 0 2.499868)
			(end 5.2578 2.499868)
			(stroke
				(width 0.1524)
				(type default)
			)
			(fill no)
			(layer "F.SilkS")
		)
		(fp_poly
			(pts
				(arc
					(start 5.2578 2.499868)
					(mid 0 7.757922)
					(end -5.2578 2.499868)
				)
			)
			(stroke
				(width 0)
				(type default)
			)
			(fill yes)
			(layer "F.SilkS")
		)
		(fp_circle
			(center 0 2.499868)
			(end 5.2578 2.499868)
			(stroke
				(width 0.1)
				(type default)
			)
			(fill no)
			(layer "F.Fab")
		)
		(pad "1" thru_hole rect
			(at 0 0 270)
			(size 1.524 1.524)
			(drill 1.016)
			(layers "*.Cu" "*.Mask")
			(remove_unused_layers no)
			(net "P12V_BRICK")
			(clearance 0)
			(padstack
				(mode front_inner_back)
				(layer "Inner"
					(shape circle)
					(size 1.524 1.524)
					(clearance 0)
				)
				(layer "B.Cu"
					(shape rect)
					(size 1.524 1.524)
					(clearance 0)
				)
			)
		)
		(pad "2" thru_hole circle
			(at 0 4.99999 270)
			(size 1.524 1.524)
			(drill 1.016)
			(layers "*.Cu" "*.Mask")
			(remove_unused_layers no)
			(net "GND")
			(clearance 0)
		)
	)
	(footprint ""
		(layer "F.Cu")
		(at 270.383 -92.085668 90)
		(property "Reference" "PR14"
			(at 0 0 90)
			(layer "F.SilkS")
			(hide yes)
			(effects
				(font
					(size 1.27 1.27)
				)
			)
		)
		(property "Value" ""
			(at 0 0 90)
			(layer "F.Fab")
			(effects
				(font
					(size 1.27 1.27)
				)
			)
		)
		(duplicate_pad_numbers_are_jumpers no)
		(fp_line
			(start 1.2954 -0.5842)
			(end 1.2954 0.5842)
			(stroke
				(width 0.1524)
				(type default)
			)
			(layer "F.SilkS")
		)
		(fp_line
			(start -1.2954 -0.5842)
			(end 1.2954 -0.5842)
			(stroke
				(width 0.1524)
				(type default)
			)
			(layer "F.SilkS")
		)
		(fp_line
			(start 1.2954 0.5842)
			(end -1.2954 0.5842)
			(stroke
				(width 0.1524)
				(type default)
			)
			(layer "F.SilkS")
		)
		(fp_line
			(start -1.2954 0.5842)
			(end -1.2954 -0.5842)
			(stroke
				(width 0.1524)
				(type default)
			)
			(layer "F.SilkS")
		)
		(fp_line
			(start 0.8636 -0.4572)
			(end 0.8636 -0.406654)
			(stroke
				(width 0.1)
				(type default)
			)
			(layer "F.Fab")
		)
		(fp_line
			(start -0.8636 -0.4572)
			(end 0.8636 -0.4572)
			(stroke
				(width 0.1)
				(type default)
			)
			(layer "F.Fab")
		)
		(fp_line
			(start 1.1938 -0.406654)
			(end 1.1938 0.4064)
			(stroke
				(width 0.1)
				(type default)
			)
			(layer "F.Fab")
		)
		(fp_line
			(start 0.8636 -0.406654)
			(end 1.1938 -0.406654)
			(stroke
				(width 0.1)
				(type default)
			)
			(layer "F.Fab")
		)
		(fp_line
			(start -0.8636 -0.406654)
			(end -0.8636 -0.4572)
			(stroke
				(width 0.1)
				(type default)
			)
			(layer "F.Fab")
		)
		(fp_line
			(start -1.1938 -0.406654)
			(end -0.8636 -0.406654)
			(stroke
				(width 0.1)
				(type default)
			)
			(layer "F.Fab")
		)
		(fp_line
			(start 1.1938 0.4064)
			(end 0.8636 0.4064)
			(stroke
				(width 0.1)
				(type default)
			)
			(layer "F.Fab")
		)
		(fp_line
			(start 0.8636 0.4064)
			(end 0.8636 0.4572)
			(stroke
				(width 0.1)
				(type default)
			)
			(layer "F.Fab")
		)
		(fp_line
			(start -0.8636 0.4064)
			(end -1.1938 0.4064)
			(stroke
				(width 0.1)
				(type default)
			)
			(layer "F.Fab")
		)
		(fp_line
			(start -1.1938 0.4064)
			(end -1.1938 -0.406654)
			(stroke
				(width 0.1)
				(type default)
			)
			(layer "F.Fab")
		)
		(fp_line
			(start -0.8636 0.4318)
			(end -0.8636 0.4064)
			(stroke
				(width 0.1)
				(type default)
			)
			(layer "F.Fab")
		)
		(fp_line
			(start 0.8636 0.4572)
			(end -0.8636 0.4572)
			(stroke
				(width 0.1)
				(type default)
			)
			(layer "F.Fab")
		)
		(fp_line
			(start -0.8636 0.4572)
			(end -0.8636 0.4318)
			(stroke
				(width 0.1)
				(type default)
			)
			(layer "F.Fab")
		)
		(pad "1" smd rect
			(at -0.7366 0)
			(size 0.7112 0.8128)
			(layers "F.Cu" "F.Mask" "F.Paste")
			(net "P52V_HS1_GATE2_R")
		)
		(pad "2" smd rect
			(at 0.7366 0)
			(size 0.7112 0.8128)
			(layers "F.Cu" "F.Mask" "F.Paste")
			(net "P52V_HS1_GATE4")
		)
	)
	(footprint ""
		(layer "F.Cu")
		(at 151.765 -49.911)
		(property "Reference" "PC39"
			(at 0 0 0)
			(layer "F.SilkS")
			(hide yes)
			(effects
				(font
					(size 1.27 1.27)
				)
			)
		)
		(property "Value" ""
			(at 0 0 0)
			(layer "F.Fab")
			(effects
				(font
					(size 1.27 1.27)
				)
			)
		)
		(duplicate_pad_numbers_are_jumpers no)
		(fp_line
			(start -1.524 -0.762)
			(end 1.524 -0.762)
			(stroke
				(width 0.1524)
				(type default)
			)
			(layer "F.SilkS")
		)
		(fp_line
			(start -1.524 0.762)
			(end -1.524 -0.762)
			(stroke
				(width 0.1524)
				(type default)
			)
			(layer "F.SilkS")
		)
		(fp_line
			(start 1.524 -0.762)
			(end 1.524 0.762)
			(stroke
				(width 0.1524)
				(type default)
			)
			(layer "F.SilkS")
		)
		(fp_line
			(start 1.524 0.762)
			(end -1.524 0.762)
			(stroke
				(width 0.1524)
				(type default)
			)
			(layer "F.SilkS")
		)
		(fp_line
			(start -1.1049 -0.724916)
			(end -1.1049 0.724916)
			(stroke
				(width 0.1)
				(type default)
			)
			(layer "F.Fab")
		)
		(fp_line
			(start -1.1049 0.724916)
			(end 1.1049 0.724916)
			(stroke
				(width 0.1)
				(type default)
			)
			(layer "F.Fab")
		)
		(fp_line
			(start 1.1049 -0.724916)
			(end -1.1049 -0.724916)
			(stroke
				(width 0.1)
				(type default)
			)
			(layer "F.Fab")
		)
		(fp_line
			(start 1.1049 0.724916)
			(end 1.1049 -0.724916)
			(stroke
				(width 0.1)
				(type default)
			)
			(layer "F.Fab")
		)
		(pad "1" smd rect
			(at -0.889 0 180)
			(size 1.016 1.27)
			(layers "F.Cu" "F.Mask" "F.Paste")
			(net "P12V_BRICK")
		)
		(pad "2" smd rect
			(at 0.889 0 180)
			(size 1.016 1.27)
			(layers "F.Cu" "F.Mask" "F.Paste")
			(net "GND")
		)
	)
)
